(kicad_pcb
	(version 20260206)
	(generator "pcbnew")
	(generator_version "10.0")
	(general
		(thickness 1.6)
		(legacy_teardrops no)
	)
	(paper "A4")
	(title_block
		(title "04192023_DAF0TMB3IC0_F0TG_MB_C_brd_V02_OCP.brd")
		(comment 1 "Grand Teton / footprint 2783 of 8354 (U26), pads 5124-5231 of 6102")
	)
	(layers
		(0 "F.Cu" signal "TOP")
		(4 "In1.Cu" signal "GND")
		(6 "In2.Cu" signal "IN1")
		(8 "In3.Cu" signal "GND1")
		(10 "In4.Cu" signal "IN2")
		(12 "In5.Cu" signal "GND2")
		(14 "In6.Cu" signal "IN3")
		(16 "In7.Cu" signal "GND3")
		(18 "In8.Cu" signal "VCC")
		(20 "In9.Cu" signal "VCC1")
		(22 "In10.Cu" signal "GND4")
		(24 "In11.Cu" signal "IN4")
		(26 "In12.Cu" signal "GND5")
		(28 "In13.Cu" signal "IN5")
		(30 "In14.Cu" signal "GND6")
		(32 "In15.Cu" signal "IN6")
		(34 "In16.Cu" signal "GND7")
		(2 "B.Cu" signal "BOTTOM")
		(9 "F.Adhes" user "F.Adhesive")
		(11 "B.Adhes" user "B.Adhesive")
		(13 "F.Paste" user "Package Geometry/Pastemask Top")
		(15 "B.Paste" user "Package Geometry/Pastemask Bottom")
		(5 "F.SilkS" user "Ref Des/Silkscreen Top")
		(7 "B.SilkS" user "Ref Des/Silkscreen Bottom")
		(1 "F.Mask" user "Board Geometry/Soldermask Top")
		(3 "B.Mask" user "Board Geometry/Soldermask Bottom")
		(17 "Dwgs.User" user "User.Drawings")
		(19 "Cmts.User" user "User.Comments")
		(21 "Eco1.User" user "User.Eco1")
		(23 "Eco2.User" user "User.Eco2")
		(25 "Edge.Cuts" user "Board Geometry/Outline")
		(27 "Margin" user)
		(31 "F.CrtYd" user "Package Geometry/Place Bound Top")
		(29 "B.CrtYd" user "Package Geometry/Place Bound Bottom")
		(35 "F.Fab" user "Ref Des/Assembly Top")
		(33 "B.Fab" user "Ref Des/Assembly Bottom")
	)
	(footprint ""
		(layer "F.Cu")
		(at 111.927894 -258.880356 180)
		(property "Reference" "U26"
			(at -45.05579 -61.794136 0)
			(unlocked yes)
			(layer "F.SilkS")
			(effects
				(font
					(size 0.7874 0.5842)
					(thickness 0.1524)
				)
			)
		)
		(property "Value" ""
			(at 0 0 180)
			(layer "F.Fab")
			(effects
				(font
					(size 1.27 1.27)
				)
			)
		)
		(duplicate_pad_numbers_are_jumpers no)
		(pad "G30" smd circle
			(at -6.89991 -31.949898 180)
			(size 0.450088 0.450088)
			(layers "F.Cu" "F.Mask" "F.Paste")
			(net "GMI_CPU1_G2_CPU0_G0_TX_DN<7>")
		)
		(pad "G31" smd circle
			(at -5.96011 -31.949898 180)
			(size 0.450088 0.450088)
			(layers "F.Cu" "F.Mask" "F.Paste")
			(net "GND")
		)
		(pad "G32" smd circle
			(at -5.020056 -31.949898 180)
			(size 0.450088 0.450088)
			(layers "F.Cu" "F.Mask" "F.Paste")
			(net "GMI_CPU1_G2_CPU0_G0_TX_DP<4>")
		)
		(pad "G33" smd circle
			(at -4.080002 -31.949898 180)
			(size 0.450088 0.450088)
			(layers "F.Cu" "F.Mask" "F.Paste")
			(net "GMI_CPU1_G2_CPU0_G0_TX_DN<4>")
		)
		(pad "G34" smd circle
			(at -3.139948 -31.949898 180)
			(size 0.450088 0.450088)
			(layers "F.Cu" "F.Mask" "F.Paste")
			(net "GND")
		)
		(pad "G35" smd circle
			(at -2.199894 -31.949898 180)
			(size 0.450088 0.450088)
			(layers "F.Cu" "F.Mask" "F.Paste")
			(net "PVDDCR_CPU0_P1")
		)
		(pad "G36" smd circle
			(at -1.260094 -31.949898 180)
			(size 0.450088 0.450088)
			(layers "F.Cu" "F.Mask" "F.Paste")
			(net "PVDDCR_CPU0_P1")
		)
		(pad "G40" smd circle
			(at 1.560068 -31.949898 180)
			(size 0.450088 0.450088)
			(layers "F.Cu" "F.Mask" "F.Paste")
			(net "PVDDCR_CPU0_P1")
		)
		(pad "G41" smd circle
			(at 2.500122 -31.949898 180)
			(size 0.450088 0.450088)
			(layers "F.Cu" "F.Mask" "F.Paste")
			(net "PVDDCR_CPU0_P1")
		)
		(pad "G42" smd circle
			(at 3.439922 -31.949898 180)
			(size 0.450088 0.450088)
			(layers "F.Cu" "F.Mask" "F.Paste")
			(net "GND")
		)
		(pad "G43" smd circle
			(at 4.379976 -31.949898 180)
			(size 0.450088 0.450088)
			(layers "F.Cu" "F.Mask" "F.Paste")
			(net "GMI_CPU0_G2_CPU1_G0_TX_DN<11>")
		)
		(pad "G44" smd circle
			(at 5.32003 -31.949898 180)
			(size 0.450088 0.450088)
			(layers "F.Cu" "F.Mask" "F.Paste")
			(net "GMI_CPU0_G2_CPU1_G0_TX_DP<11>")
		)
		(pad "G45" smd circle
			(at 6.260084 -31.949898 180)
			(size 0.450088 0.450088)
			(layers "F.Cu" "F.Mask" "F.Paste")
			(net "GND")
		)
		(pad "G46" smd circle
			(at 7.199884 -31.949898 180)
			(size 0.450088 0.450088)
			(layers "F.Cu" "F.Mask" "F.Paste")
			(net "GMI_CPU0_G2_CPU1_G0_TX_DN<8>")
		)
		(pad "G47" smd circle
			(at 8.139938 -31.949898 180)
			(size 0.450088 0.450088)
			(layers "F.Cu" "F.Mask" "F.Paste")
			(net "GMI_CPU0_G2_CPU1_G0_TX_DP<8>")
		)
		(pad "G48" smd circle
			(at 9.079992 -31.949898 180)
			(size 0.450088 0.450088)
			(layers "F.Cu" "F.Mask" "F.Paste")
			(net "GND")
		)
		(pad "G49" smd circle
			(at 10.020046 -31.949898 180)
			(size 0.450088 0.450088)
			(layers "F.Cu" "F.Mask" "F.Paste")
			(net "GMI_CPU0_G2_CPU1_G0_TX_DN<5>")
		)
		(pad "G50" smd circle
			(at 10.9601 -31.949898 180)
			(size 0.450088 0.450088)
			(layers "F.Cu" "F.Mask" "F.Paste")
			(net "GMI_CPU0_G2_CPU1_G0_TX_DP<5>")
		)
		(pad "G51" smd circle
			(at 11.8999 -31.949898 180)
			(size 0.450088 0.450088)
			(layers "F.Cu" "F.Mask" "F.Paste")
			(net "GND")
		)
		(pad "G52" smd circle
			(at 12.839954 -31.949898 180)
			(size 0.450088 0.450088)
			(layers "F.Cu" "F.Mask" "F.Paste")
			(net "GMI_CPU0_G2_CPU1_G0_TX_DN<2>")
		)
		(pad "G53" smd circle
			(at 13.780008 -31.949898 180)
			(size 0.450088 0.450088)
			(layers "F.Cu" "F.Mask" "F.Paste")
			(net "GMI_CPU0_G2_CPU1_G0_TX_DP<2>")
		)
		(pad "G54" smd circle
			(at 14.720062 -31.949898 180)
			(size 0.450088 0.450088)
			(layers "F.Cu" "F.Mask" "F.Paste")
			(net "GND")
		)
		(pad "G55" smd circle
			(at 15.660116 -31.949898 180)
			(size 0.450088 0.450088)
			(layers "F.Cu" "F.Mask" "F.Paste")
			(net "M_C_CPU1_SA_DQ<3>")
		)
		(pad "G56" smd circle
			(at 16.599916 -31.949898 180)
			(size 0.450088 0.450088)
			(layers "F.Cu" "F.Mask" "F.Paste")
			(net "GND")
		)
		(pad "G57" smd circle
			(at 17.53997 -31.949898 180)
			(size 0.450088 0.450088)
			(layers "F.Cu" "F.Mask" "F.Paste")
			(net "M_C_CPU1_SA_DQS_DP<0>")
		)
		(pad "G58" smd circle
			(at 18.480024 -31.949898 180)
			(size 0.450088 0.450088)
			(layers "F.Cu" "F.Mask" "F.Paste")
			(net "GND")
		)
		(pad "G59" smd circle
			(at 19.420078 -31.949898 180)
			(size 0.450088 0.450088)
			(layers "F.Cu" "F.Mask" "F.Paste")
			(net "M_D_CPU1_SA_DQ<3>")
		)
		(pad "G60" smd circle
			(at 20.359878 -31.949898 180)
			(size 0.450088 0.450088)
			(layers "F.Cu" "F.Mask" "F.Paste")
			(net "M_D_CPU1_SA_DQS_DP<0>")
		)
		(pad "G61" smd circle
			(at 21.299932 -31.949898 180)
			(size 0.450088 0.450088)
			(layers "F.Cu" "F.Mask" "F.Paste")
			(net "GND")
		)
		(pad "G62" smd circle
			(at 22.239986 -31.949898 180)
			(size 0.450088 0.450088)
			(layers "F.Cu" "F.Mask" "F.Paste")
			(net "M_B_CPU1_SA_DQ<3>")
		)
		(pad "G63" smd circle
			(at 23.18004 -31.949898 180)
			(size 0.450088 0.450088)
			(layers "F.Cu" "F.Mask" "F.Paste")
			(net "GND")
		)
		(pad "G64" smd circle
			(at 24.120094 -31.949898 180)
			(size 0.450088 0.450088)
			(layers "F.Cu" "F.Mask" "F.Paste")
			(net "M_B_CPU1_SA_DQS_DP<0>")
		)
		(pad "G65" smd circle
			(at 25.059894 -31.949898 180)
			(size 0.450088 0.450088)
			(layers "F.Cu" "F.Mask" "F.Paste")
			(net "GND")
		)
		(pad "G66" smd circle
			(at 25.999948 -31.949898 180)
			(size 0.450088 0.450088)
			(layers "F.Cu" "F.Mask" "F.Paste")
			(net "M_F_CPU1_SA_DQ<3>")
		)
		(pad "G67" smd circle
			(at 26.940002 -31.949898 180)
			(size 0.450088 0.450088)
			(layers "F.Cu" "F.Mask" "F.Paste")
			(net "M_F_CPU1_SA_DQS_DP<0>")
		)
		(pad "G68" smd circle
			(at 27.880056 -31.949898 180)
			(size 0.450088 0.450088)
			(layers "F.Cu" "F.Mask" "F.Paste")
			(net "GND")
		)
		(pad "G69" smd circle
			(at 28.82011 -31.949898 180)
			(size 0.450088 0.450088)
			(layers "F.Cu" "F.Mask" "F.Paste")
			(net "M_E_CPU1_SA_DQ<3>")
		)
		(pad "G70" smd circle
			(at 29.75991 -31.949898 180)
			(size 0.450088 0.450088)
			(layers "F.Cu" "F.Mask" "F.Paste")
			(net "GND")
		)
		(pad "G71" smd circle
			(at 30.699964 -31.949898 180)
			(size 0.450088 0.450088)
			(layers "F.Cu" "F.Mask" "F.Paste")
			(net "M_E_CPU1_SA_DQS_DP<0>")
		)
		(pad "G72" smd circle
			(at 31.640018 -31.949898 180)
			(size 0.450088 0.450088)
			(layers "F.Cu" "F.Mask" "F.Paste")
			(net "GND")
		)
		(pad "G73" smd circle
			(at 32.580072 -31.949898 180)
			(size 0.450088 0.450088)
			(layers "F.Cu" "F.Mask" "F.Paste")
			(net "M_A_CPU1_SA_DQ<3>")
		)
		(pad "G74" smd circle
			(at 33.519872 -31.949898 180)
			(size 0.450088 0.450088)
			(layers "F.Cu" "F.Mask" "F.Paste")
			(net "M_A_CPU1_SA_DQS_DP<0>")
		)
		(pad "G75" smd circle
			(at 34.459926 -31.949898 180)
			(size 0.450088 0.450088)
			(layers "F.Cu" "F.Mask" "F.Paste")
			(net "GND")
		)
		(pad "H2" smd circle
			(at -33.690052 -31.139892 180)
			(size 0.450088 0.450088)
			(layers "F.Cu" "F.Mask" "F.Paste")
			(net "M_G_CPU1_SA_DQS_DN<0>")
		)
		(pad "H3" smd circle
			(at -32.749998 -31.139892 180)
			(size 0.450088 0.450088)
			(layers "F.Cu" "F.Mask" "F.Paste")
			(net "GND")
		)
		(pad "H4" smd circle
			(at -31.809944 -31.139892 180)
			(size 0.450088 0.450088)
			(layers "F.Cu" "F.Mask" "F.Paste")
			(net "M_G_CPU1_SA_DQS_DN<5>")
		)
		(pad "H5" smd circle
			(at -30.86989 -31.139892 180)
			(size 0.450088 0.450088)
			(layers "F.Cu" "F.Mask" "F.Paste")
			(net "PVDDCR_SOC_P1")
		)
		(pad "H6" smd circle
			(at -29.93009 -31.139892 180)
			(size 0.450088 0.450088)
			(layers "F.Cu" "F.Mask" "F.Paste")
			(net "M_K_CPU1_SA_DQS_DN<0>")
		)
		(pad "H7" smd circle
			(at -28.990036 -31.139892 180)
			(size 0.450088 0.450088)
			(layers "F.Cu" "F.Mask" "F.Paste")
			(net "M_K_CPU1_SA_DQS_DN<5>")
		)
		(pad "H8" smd circle
			(at -28.049982 -31.139892 180)
			(size 0.450088 0.450088)
			(layers "F.Cu" "F.Mask" "F.Paste")
			(net "GND")
		)
		(pad "H9" smd circle
			(at -27.109928 -31.139892 180)
			(size 0.450088 0.450088)
			(layers "F.Cu" "F.Mask" "F.Paste")
			(net "M_L_CPU1_SA_DQS_DN<0>")
		)
		(pad "H10" smd circle
			(at -26.170128 -31.139892 180)
			(size 0.450088 0.450088)
			(layers "F.Cu" "F.Mask" "F.Paste")
			(net "GND")
		)
		(pad "H11" smd circle
			(at -25.230074 -31.139892 180)
			(size 0.450088 0.450088)
			(layers "F.Cu" "F.Mask" "F.Paste")
			(net "M_L_CPU1_SA_DQS_DN<5>")
		)
		(pad "H12" smd circle
			(at -24.29002 -31.139892 180)
			(size 0.450088 0.450088)
			(layers "F.Cu" "F.Mask" "F.Paste")
			(net "PVDDCR_SOC_P1")
		)
		(pad "H13" smd circle
			(at -23.349966 -31.139892 180)
			(size 0.450088 0.450088)
			(layers "F.Cu" "F.Mask" "F.Paste")
			(net "M_H_CPU1_SA_DQS_DN<0>")
		)
		(pad "H14" smd circle
			(at -22.409912 -31.139892 180)
			(size 0.450088 0.450088)
			(layers "F.Cu" "F.Mask" "F.Paste")
			(net "M_H_CPU1_SA_DQS_DN<5>")
		)
		(pad "H15" smd circle
			(at -21.470112 -31.139892 180)
			(size 0.450088 0.450088)
			(layers "F.Cu" "F.Mask" "F.Paste")
			(net "GND")
		)
		(pad "H16" smd circle
			(at -20.530058 -31.139892 180)
			(size 0.450088 0.450088)
			(layers "F.Cu" "F.Mask" "F.Paste")
			(net "M_J_CPU1_SA_DQS_DN<0>")
		)
		(pad "H17" smd circle
			(at -19.590004 -31.139892 180)
			(size 0.450088 0.450088)
			(layers "F.Cu" "F.Mask" "F.Paste")
			(net "GND")
		)
		(pad "H18" smd circle
			(at -18.64995 -31.139892 180)
			(size 0.450088 0.450088)
			(layers "F.Cu" "F.Mask" "F.Paste")
			(net "M_J_CPU1_SA_DQS_DN<5>")
		)
		(pad "H19" smd circle
			(at -17.709896 -31.139892 180)
			(size 0.450088 0.450088)
			(layers "F.Cu" "F.Mask" "F.Paste")
			(net "PVDDCR_SOC_P1")
		)
		(pad "H20" smd circle
			(at -16.770096 -31.139892 180)
			(size 0.450088 0.450088)
			(layers "F.Cu" "F.Mask" "F.Paste")
			(net "M_I_CPU1_SA_DQS_DN<0>")
		)
		(pad "H21" smd circle
			(at -15.830042 -31.139892 180)
			(size 0.450088 0.450088)
			(layers "F.Cu" "F.Mask" "F.Paste")
			(net "M_I_CPU1_SA_DQS_DN<5>")
		)
		(pad "H22" smd circle
			(at -14.889988 -31.139892 180)
			(size 0.450088 0.450088)
			(layers "F.Cu" "F.Mask" "F.Paste")
			(net "GND")
		)
		(pad "H23" smd circle
			(at -13.949934 -31.139892 180)
			(size 0.450088 0.450088)
			(layers "F.Cu" "F.Mask" "F.Paste")
			(net "PVDDCR_CPU0_P1")
		)
		(pad "H24" smd circle
			(at -13.00988 -31.139892 180)
			(size 0.450088 0.450088)
			(layers "F.Cu" "F.Mask" "F.Paste")
			(net "PVDDCR_CPU0_P1")
		)
		(pad "H25" smd circle
			(at -12.07008 -31.139892 180)
			(size 0.450088 0.450088)
			(layers "F.Cu" "F.Mask" "F.Paste")
			(net "GND")
		)
		(pad "H26" smd circle
			(at -11.130026 -31.139892 180)
			(size 0.450088 0.450088)
			(layers "F.Cu" "F.Mask" "F.Paste")
			(net "PVDDCR_CPU0_P1")
		)
		(pad "H27" smd circle
			(at -10.189972 -31.139892 180)
			(size 0.450088 0.450088)
			(layers "F.Cu" "F.Mask" "F.Paste")
			(net "PVDDCR_CPU0_P1")
		)
		(pad "H28" smd circle
			(at -9.249918 -31.139892 180)
			(size 0.450088 0.450088)
			(layers "F.Cu" "F.Mask" "F.Paste")
			(net "GND")
		)
		(pad "H29" smd circle
			(at -8.310118 -31.139892 180)
			(size 0.450088 0.450088)
			(layers "F.Cu" "F.Mask" "F.Paste")
			(net "PVDDCR_CPU0_P1")
		)
		(pad "H30" smd circle
			(at -7.370064 -31.139892 180)
			(size 0.450088 0.450088)
			(layers "F.Cu" "F.Mask" "F.Paste")
			(net "PVDDCR_CPU0_P1")
		)
		(pad "H31" smd circle
			(at -6.43001 -31.139892 180)
			(size 0.450088 0.450088)
			(layers "F.Cu" "F.Mask" "F.Paste")
			(net "GND")
		)
		(pad "H32" smd circle
			(at -5.489956 -31.139892 180)
			(size 0.450088 0.450088)
			(layers "F.Cu" "F.Mask" "F.Paste")
			(net "PVDDCR_CPU0_P1")
		)
		(pad "H33" smd circle
			(at -4.549902 -31.139892 180)
			(size 0.450088 0.450088)
			(layers "F.Cu" "F.Mask" "F.Paste")
			(net "PVDDCR_CPU0_P1")
		)
		(pad "H34" smd circle
			(at -3.610102 -31.139892 180)
			(size 0.450088 0.450088)
			(layers "F.Cu" "F.Mask" "F.Paste")
			(net "GND")
		)
		(pad "H35" smd circle
			(at -2.670048 -31.139892 180)
			(size 0.450088 0.450088)
			(layers "F.Cu" "F.Mask" "F.Paste")
			(net "GMI_CPU1_G2_CPU0_G0_TX_DP<2>")
		)
		(pad "H36" smd circle
			(at -1.729994 -31.139892 180)
			(size 0.450088 0.450088)
			(layers "F.Cu" "F.Mask" "F.Paste")
			(net "GMI_CPU1_G2_CPU0_G0_TX_DN<2>")
		)
		(pad "H37" smd circle
			(at -0.78994 -31.139892 180)
			(size 0.450088 0.450088)
			(layers "F.Cu" "F.Mask" "F.Paste")
			(net "GND")
		)
		(pad "H39" smd circle
			(at 1.089914 -31.139892 180)
			(size 0.450088 0.450088)
			(layers "F.Cu" "F.Mask" "F.Paste")
			(net "GND")
		)
		(pad "H40" smd circle
			(at 2.029968 -31.139892 180)
			(size 0.450088 0.450088)
			(layers "F.Cu" "F.Mask" "F.Paste")
			(net "GMI_CPU0_G2_CPU1_G0_TX_DN<13>")
		)
		(pad "H41" smd circle
			(at 2.970022 -31.139892 180)
			(size 0.450088 0.450088)
			(layers "F.Cu" "F.Mask" "F.Paste")
			(net "GMI_CPU0_G2_CPU1_G0_TX_DP<13>")
		)
		(pad "H42" smd circle
			(at 3.910076 -31.139892 180)
			(size 0.450088 0.450088)
			(layers "F.Cu" "F.Mask" "F.Paste")
			(net "GND")
		)
		(pad "H43" smd circle
			(at 4.849876 -31.139892 180)
			(size 0.450088 0.450088)
			(layers "F.Cu" "F.Mask" "F.Paste")
			(net "PVDDCR_CPU0_P1")
		)
		(pad "H44" smd circle
			(at 5.78993 -31.139892 180)
			(size 0.450088 0.450088)
			(layers "F.Cu" "F.Mask" "F.Paste")
			(net "PVDDCR_CPU0_P1")
		)
		(pad "H45" smd circle
			(at 6.729984 -31.139892 180)
			(size 0.450088 0.450088)
			(layers "F.Cu" "F.Mask" "F.Paste")
			(net "GND")
		)
		(pad "H46" smd circle
			(at 7.670038 -31.139892 180)
			(size 0.450088 0.450088)
			(layers "F.Cu" "F.Mask" "F.Paste")
			(net "PVDDCR_CPU0_P1")
		)
		(pad "H47" smd circle
			(at 8.610092 -31.139892 180)
			(size 0.450088 0.450088)
			(layers "F.Cu" "F.Mask" "F.Paste")
			(net "PVDDCR_CPU0_P1")
		)
		(pad "H48" smd circle
			(at 9.549892 -31.139892 180)
			(size 0.450088 0.450088)
			(layers "F.Cu" "F.Mask" "F.Paste")
			(net "GND")
		)
		(pad "H49" smd circle
			(at 10.489946 -31.139892 180)
			(size 0.450088 0.450088)
			(layers "F.Cu" "F.Mask" "F.Paste")
			(net "PVDDCR_CPU0_P1")
		)
		(pad "H50" smd circle
			(at 11.43 -31.139892 180)
			(size 0.450088 0.450088)
			(layers "F.Cu" "F.Mask" "F.Paste")
			(net "PVDDCR_CPU0_P1")
		)
		(pad "H51" smd circle
			(at 12.370054 -31.139892 180)
			(size 0.450088 0.450088)
			(layers "F.Cu" "F.Mask" "F.Paste")
			(net "GND")
		)
		(pad "H52" smd circle
			(at 13.310108 -31.139892 180)
			(size 0.450088 0.450088)
			(layers "F.Cu" "F.Mask" "F.Paste")
			(net "PVDDCR_CPU0_P1")
		)
		(pad "H53" smd circle
			(at 14.249908 -31.139892 180)
			(size 0.450088 0.450088)
			(layers "F.Cu" "F.Mask" "F.Paste")
			(net "PVDDCR_CPU0_P1")
		)
		(pad "H54" smd circle
			(at 15.189962 -31.139892 180)
			(size 0.450088 0.450088)
			(layers "F.Cu" "F.Mask" "F.Paste")
			(net "GND")
		)
		(pad "H55" smd circle
			(at 16.130016 -31.139892 180)
			(size 0.450088 0.450088)
			(layers "F.Cu" "F.Mask" "F.Paste")
			(net "M_C_CPU1_SA_DQS_DN<5>")
		)
		(pad "H56" smd circle
			(at 17.07007 -31.139892 180)
			(size 0.450088 0.450088)
			(layers "F.Cu" "F.Mask" "F.Paste")
			(net "M_C_CPU1_SA_DQS_DN<0>")
		)
		(pad "H57" smd circle
			(at 18.010124 -31.139892 180)
			(size 0.450088 0.450088)
			(layers "F.Cu" "F.Mask" "F.Paste")
			(net "PVDDIO_P1")
		)
		(pad "H58" smd circle
			(at 18.949924 -31.139892 180)
			(size 0.450088 0.450088)
			(layers "F.Cu" "F.Mask" "F.Paste")
			(net "M_D_CPU1_SA_DQS_DN<5>")
		)
		(pad "H59" smd circle
			(at 19.889978 -31.139892 180)
			(size 0.450088 0.450088)
			(layers "F.Cu" "F.Mask" "F.Paste")
			(net "GND")
		)
		(pad "H60" smd circle
			(at 20.830032 -31.139892 180)
			(size 0.450088 0.450088)
			(layers "F.Cu" "F.Mask" "F.Paste")
			(net "M_D_CPU1_SA_DQS_DN<0>")
		)
		(pad "H61" smd circle
			(at 21.770086 -31.139892 180)
			(size 0.450088 0.450088)
			(layers "F.Cu" "F.Mask" "F.Paste")
			(net "GND")
		)
		(pad "H62" smd circle
			(at 22.709886 -31.139892 180)
			(size 0.450088 0.450088)
			(layers "F.Cu" "F.Mask" "F.Paste")
			(net "M_B_CPU1_SA_DQS_DN<5>")
		)
		(pad "H63" smd circle
			(at 23.64994 -31.139892 180)
			(size 0.450088 0.450088)
			(layers "F.Cu" "F.Mask" "F.Paste")
			(net "M_B_CPU1_SA_DQS_DN<0>")
		)
		(pad "H64" smd circle
			(at 24.589994 -31.139892 180)
			(size 0.450088 0.450088)
			(layers "F.Cu" "F.Mask" "F.Paste")
			(net "PVDDIO_P1")
		)
		(pad "H65" smd circle
			(at 25.530048 -31.139892 180)
			(size 0.450088 0.450088)
			(layers "F.Cu" "F.Mask" "F.Paste")
			(net "M_F_CPU1_SA_DQS_DN<5>")
		)
		(pad "H66" smd circle
			(at 26.470102 -31.139892 180)
			(size 0.450088 0.450088)
			(layers "F.Cu" "F.Mask" "F.Paste")
			(net "GND")
		)
		(pad "H67" smd circle
			(at 27.409902 -31.139892 180)
			(size 0.450088 0.450088)
			(layers "F.Cu" "F.Mask" "F.Paste")
			(net "M_F_CPU1_SA_DQS_DN<0>")
		)
	)
)
